(kicad_pcb
	(version 20260206)
	(generator "pcbnew")
	(generator_version "10.0")
	(general
		(thickness 1.6)
		(legacy_teardrops no)
	)
	(paper "A4")
	(title_block
		(title "01162023_DA0F0TEBIF0_F0T_Expander_BD_F_brd_V02_OCP.brd")
		(comment 1 "Grand Teton / footprints 7086-7093 of 9728")
	)
	(layers
		(0 "F.Cu" signal "TOP")
		(4 "In1.Cu" signal "GND")
		(6 "In2.Cu" signal "VCC")
		(8 "In3.Cu" signal "VCC1")
		(10 "In4.Cu" signal "GND1")
		(12 "In5.Cu" signal "IN1")
		(14 "In6.Cu" signal "GND2")
		(16 "In7.Cu" signal "IN2")
		(18 "In8.Cu" signal "GND3")
		(20 "In9.Cu" signal "IN3")
		(22 "In10.Cu" signal "GND4")
		(24 "In11.Cu" signal "IN4")
		(26 "In12.Cu" signal "GND5")
		(28 "In13.Cu" signal "IN5")
		(30 "In14.Cu" signal "GND6")
		(32 "In15.Cu" signal "IN6")
		(34 "In16.Cu" signal "GND7")
		(2 "B.Cu" signal "BOTTOM")
		(9 "F.Adhes" user "F.Adhesive")
		(11 "B.Adhes" user "B.Adhesive")
		(13 "F.Paste" user "Package Geometry/Pastemask Top")
		(15 "B.Paste" user "Package Geometry/Pastemask Bottom")
		(5 "F.SilkS" user "Ref Des/Silkscreen Top")
		(7 "B.SilkS" user "Ref Des/Silkscreen Bottom")
		(1 "F.Mask" user "Board Geometry/Soldermask Top")
		(3 "B.Mask" user "Board Geometry/Soldermask Bottom")
		(17 "Dwgs.User" user "User.Drawings")
		(19 "Cmts.User" user "User.Comments")
		(21 "Eco1.User" user "User.Eco1")
		(23 "Eco2.User" user "User.Eco2")
		(25 "Edge.Cuts" user "Board Geometry/Outline")
		(27 "Margin" user)
		(31 "F.CrtYd" user "Package Geometry/Place Bound Top")
		(29 "B.CrtYd" user "Package Geometry/Place Bound Bottom")
		(35 "F.Fab" user "Ref Des/Assembly Top")
		(33 "B.Fab" user "Ref Des/Assembly Bottom")
	)
	(footprint ""
		(layer "F.Cu")
		(at 315.586364 -356.244906 90)
		(property "Reference" "C545"
			(at 0 0 90)
			(layer "F.SilkS")
			(hide yes)
			(effects
				(font
					(size 1.27 1.27)
				)
			)
		)
		(property "Value" ""
			(at 0 0 90)
			(layer "F.Fab")
			(effects
				(font
					(size 1.27 1.27)
				)
			)
		)
		(duplicate_pad_numbers_are_jumpers no)
		(fp_line
			(start 0.299974 -0.150114)
			(end 0.299974 0.150114)
			(stroke
				(width 0.1)
				(type default)
			)
			(layer "F.Fab")
		)
		(fp_line
			(start -0.299974 -0.150114)
			(end 0.299974 -0.150114)
			(stroke
				(width 0.1)
				(type default)
			)
			(layer "F.Fab")
		)
		(fp_line
			(start 0.299974 0.150114)
			(end -0.299974 0.150114)
			(stroke
				(width 0.1)
				(type default)
			)
			(layer "F.Fab")
		)
		(fp_line
			(start -0.299974 0.150114)
			(end -0.299974 -0.150114)
			(stroke
				(width 0.1)
				(type default)
			)
			(layer "F.Fab")
		)
		(pad "1" smd rect
			(at -0.2667 0 90)
			(size 0.3048 0.381)
			(layers "F.Cu" "F.Mask" "F.Paste")
			(net "P5E_PEX2_STN5_TX_DP<82>")
		)
		(pad "2" smd rect
			(at 0.2667 0 90)
			(size 0.3048 0.381)
			(layers "F.Cu" "F.Mask" "F.Paste")
			(net "P5E_PEX2_STN5_TX_C_DP<82>")
		)
	)
	(footprint ""
		(layer "F.Cu")
		(at 393.669266 -87.214202 180)
		(property "Reference" "R1778"
			(at 0 0 180)
			(layer "F.SilkS")
			(hide yes)
			(effects
				(font
					(size 1.27 1.27)
				)
			)
		)
		(property "Value" ""
			(at 0 0 180)
			(layer "F.Fab")
			(effects
				(font
					(size 1.27 1.27)
				)
			)
		)
		(duplicate_pad_numbers_are_jumpers no)
		(fp_line
			(start 0.7874 0.4064)
			(end -0.7874 0.4064)
			(stroke
				(width 0.1524)
				(type default)
			)
			(layer "F.SilkS")
		)
		(fp_line
			(start 0.7874 -0.4064)
			(end 0.7874 0.4064)
			(stroke
				(width 0.1524)
				(type default)
			)
			(layer "F.SilkS")
		)
		(fp_line
			(start -0.7874 0.4064)
			(end -0.7874 -0.4064)
			(stroke
				(width 0.1524)
				(type default)
			)
			(layer "F.SilkS")
		)
		(fp_line
			(start -0.7874 -0.4064)
			(end 0.7874 -0.4064)
			(stroke
				(width 0.1524)
				(type default)
			)
			(layer "F.SilkS")
		)
		(fp_line
			(start 0.67945 0.3048)
			(end 0.120396 0.3048)
			(stroke
				(width 0.1)
				(type default)
			)
			(layer "F.Fab")
		)
		(fp_line
			(start 0.67945 -0.3048)
			(end 0.67945 0.3048)
			(stroke
				(width 0.1)
				(type default)
			)
			(layer "F.Fab")
		)
		(fp_line
			(start 0.12065 -0.2794)
			(end 0.12065 -0.3048)
			(stroke
				(width 0.1)
				(type default)
			)
			(layer "F.Fab")
		)
		(fp_line
			(start 0.12065 -0.3048)
			(end 0.67945 -0.3048)
			(stroke
				(width 0.1)
				(type default)
			)
			(layer "F.Fab")
		)
		(fp_line
			(start 0.120396 0.3048)
			(end 0.120396 0.2794)
			(stroke
				(width 0.1)
				(type default)
			)
			(layer "F.Fab")
		)
		(fp_line
			(start 0.120396 0.2794)
			(end -0.12065 0.2794)
			(stroke
				(width 0.1)
				(type default)
			)
			(layer "F.Fab")
		)
		(fp_line
			(start -0.12065 0.3048)
			(end -0.67945 0.3048)
			(stroke
				(width 0.1)
				(type default)
			)
			(layer "F.Fab")
		)
		(fp_line
			(start -0.12065 0.2794)
			(end -0.12065 0.3048)
			(stroke
				(width 0.1)
				(type default)
			)
			(layer "F.Fab")
		)
		(fp_line
			(start -0.12065 -0.2794)
			(end 0.12065 -0.2794)
			(stroke
				(width 0.1)
				(type default)
			)
			(layer "F.Fab")
		)
		(fp_line
			(start -0.12065 -0.305054)
			(end -0.12065 -0.2794)
			(stroke
				(width 0.1)
				(type default)
			)
			(layer "F.Fab")
		)
		(fp_line
			(start -0.67945 0.3048)
			(end -0.67945 -0.305054)
			(stroke
				(width 0.1)
				(type default)
			)
			(layer "F.Fab")
		)
		(fp_line
			(start -0.67945 -0.305054)
			(end -0.12065 -0.305054)
			(stroke
				(width 0.1)
				(type default)
			)
			(layer "F.Fab")
		)
		(pad "1" smd circle
			(at -0.40005 0 180)
			(size 0 0)
			(layers "F.Cu" "F.Mask" "F.Paste")
			(net "SMB_BIC_I2C6_MUX_FRU_R_SDA")
		)
		(pad "2" smd circle
			(at 0.40005 0 180)
			(size 0 0)
			(layers "F.Cu" "F.Mask" "F.Paste")
			(net "SMB_BIC_I2C6_MUX_FRU_SDA")
		)
	)
	(footprint ""
		(layer "F.Cu")
		(at 70.673722 -343.952322 90)
		(property "Reference" "C119"
			(at 0 0 90)
			(layer "F.SilkS")
			(hide yes)
			(effects
				(font
					(size 1.27 1.27)
				)
			)
		)
		(property "Value" ""
			(at 0 0 90)
			(layer "F.Fab")
			(effects
				(font
					(size 1.27 1.27)
				)
			)
		)
		(duplicate_pad_numbers_are_jumpers no)
		(fp_line
			(start 0.299974 -0.150114)
			(end 0.299974 0.150114)
			(stroke
				(width 0.1)
				(type default)
			)
			(layer "F.Fab")
		)
		(fp_line
			(start -0.299974 -0.150114)
			(end 0.299974 -0.150114)
			(stroke
				(width 0.1)
				(type default)
			)
			(layer "F.Fab")
		)
		(fp_line
			(start 0.299974 0.150114)
			(end -0.299974 0.150114)
			(stroke
				(width 0.1)
				(type default)
			)
			(layer "F.Fab")
		)
		(fp_line
			(start -0.299974 0.150114)
			(end -0.299974 -0.150114)
			(stroke
				(width 0.1)
				(type default)
			)
			(layer "F.Fab")
		)
		(pad "1" smd rect
			(at -0.2667 0 90)
			(size 0.3048 0.381)
			(layers "F.Cu" "F.Mask" "F.Paste")
			(net "P5E_PEX0_STN5_TX_DP<84>")
		)
		(pad "2" smd rect
			(at 0.2667 0 90)
			(size 0.3048 0.381)
			(layers "F.Cu" "F.Mask" "F.Paste")
			(net "P5E_PEX0_STN5_TX_C_DP<84>")
		)
	)
	(footprint ""
		(layer "F.Cu")
		(at 152.738328 -134.923276)
		(property "Reference" "C247"
			(at 0 0 0)
			(layer "F.SilkS")
			(hide yes)
			(effects
				(font
					(size 1.27 1.27)
				)
			)
		)
		(property "Value" ""
			(at 0 0 0)
			(layer "F.Fab")
			(effects
				(font
					(size 1.27 1.27)
				)
			)
		)
		(duplicate_pad_numbers_are_jumpers no)
		(fp_line
			(start -0.299974 -0.150114)
			(end 0.299974 -0.150114)
			(stroke
				(width 0.1)
				(type default)
			)
			(layer "F.Fab")
		)
		(fp_line
			(start -0.299974 0.150114)
			(end -0.299974 -0.150114)
			(stroke
				(width 0.1)
				(type default)
			)
			(layer "F.Fab")
		)
		(fp_line
			(start 0.299974 -0.150114)
			(end 0.299974 0.150114)
			(stroke
				(width 0.1)
				(type default)
			)
			(layer "F.Fab")
		)
		(fp_line
			(start 0.299974 0.150114)
			(end -0.299974 0.150114)
			(stroke
				(width 0.1)
				(type default)
			)
			(layer "F.Fab")
		)
		(pad "1" smd rect
			(at -0.2667 0)
			(size 0.3048 0.381)
			(layers "F.Cu" "F.Mask" "F.Paste")
			(net "P5E_PEX1_STN1_TX_DN<30>")
		)
		(pad "2" smd rect
			(at 0.2667 0)
			(size 0.3048 0.381)
			(layers "F.Cu" "F.Mask" "F.Paste")
			(net "P5E_PEX1_STN1_TX_C_DN<30>")
		)
	)
	(footprint ""
		(layer "F.Cu")
		(at 80.019398 -118.670324 180)
		(property "Reference" "C32"
			(at 0 0 180)
			(layer "F.SilkS")
			(hide yes)
			(effects
				(font
					(size 1.27 1.27)
				)
			)
		)
		(property "Value" ""
			(at 0 0 180)
			(layer "F.Fab")
			(effects
				(font
					(size 1.27 1.27)
				)
			)
		)
		(duplicate_pad_numbers_are_jumpers no)
		(fp_line
			(start 0.299974 0.150114)
			(end -0.299974 0.150114)
			(stroke
				(width 0.1)
				(type default)
			)
			(layer "F.Fab")
		)
		(fp_line
			(start 0.299974 -0.150114)
			(end 0.299974 0.150114)
			(stroke
				(width 0.1)
				(type default)
			)
			(layer "F.Fab")
		)
		(fp_line
			(start -0.299974 0.150114)
			(end -0.299974 -0.150114)
			(stroke
				(width 0.1)
				(type default)
			)
			(layer "F.Fab")
		)
		(fp_line
			(start -0.299974 -0.150114)
			(end 0.299974 -0.150114)
			(stroke
				(width 0.1)
				(type default)
			)
			(layer "F.Fab")
		)
		(pad "1" smd rect
			(at -0.2667 0 180)
			(size 0.3048 0.381)
			(layers "F.Cu" "F.Mask" "F.Paste")
			(net "P5E_PEX0_STN0_TX_DN<0>")
		)
		(pad "2" smd rect
			(at 0.2667 0 180)
			(size 0.3048 0.381)
			(layers "F.Cu" "F.Mask" "F.Paste")
			(net "P5E_PEX0_STN0_TX_C_DN<0>")
		)
	)
	(footprint ""
		(layer "F.Cu")
		(at 88.65235 -116.416836 180)
		(property "Reference" "PC662"
			(at 0 0 180)
			(layer "F.SilkS")
			(hide yes)
			(effects
				(font
					(size 1.27 1.27)
				)
			)
		)
		(property "Value" ""
			(at 0 0 180)
			(layer "F.Fab")
			(effects
				(font
					(size 1.27 1.27)
				)
			)
		)
		(duplicate_pad_numbers_are_jumpers no)
		(fp_line
			(start 0.7874 0.4064)
			(end -0.7874 0.4064)
			(stroke
				(width 0.1524)
				(type default)
			)
			(layer "F.SilkS")
		)
		(fp_line
			(start 0.7874 -0.4064)
			(end 0.7874 0.4064)
			(stroke
				(width 0.1524)
				(type default)
			)
			(layer "F.SilkS")
		)
		(fp_line
			(start -0.7874 0.4064)
			(end -0.7874 -0.4064)
			(stroke
				(width 0.1524)
				(type default)
			)
			(layer "F.SilkS")
		)
		(fp_line
			(start -0.7874 -0.4064)
			(end 0.7874 -0.4064)
			(stroke
				(width 0.1524)
				(type default)
			)
			(layer "F.SilkS")
		)
		(fp_line
			(start 0.67945 0.3048)
			(end 0.120396 0.3048)
			(stroke
				(width 0.1)
				(type default)
			)
			(layer "F.Fab")
		)
		(fp_line
			(start 0.67945 -0.3048)
			(end 0.67945 0.3048)
			(stroke
				(width 0.1)
				(type default)
			)
			(layer "F.Fab")
		)
		(fp_line
			(start 0.12065 -0.2794)
			(end 0.12065 -0.3048)
			(stroke
				(width 0.1)
				(type default)
			)
			(layer "F.Fab")
		)
		(fp_line
			(start 0.12065 -0.3048)
			(end 0.67945 -0.3048)
			(stroke
				(width 0.1)
				(type default)
			)
			(layer "F.Fab")
		)
		(fp_line
			(start 0.120396 0.3048)
			(end 0.120396 0.2794)
			(stroke
				(width 0.1)
				(type default)
			)
			(layer "F.Fab")
		)
		(fp_line
			(start 0.120396 0.2794)
			(end -0.12065 0.2794)
			(stroke
				(width 0.1)
				(type default)
			)
			(layer "F.Fab")
		)
		(fp_line
			(start -0.12065 0.3048)
			(end -0.67945 0.3048)
			(stroke
				(width 0.1)
				(type default)
			)
			(layer "F.Fab")
		)
		(fp_line
			(start -0.12065 0.2794)
			(end -0.12065 0.3048)
			(stroke
				(width 0.1)
				(type default)
			)
			(layer "F.Fab")
		)
		(fp_line
			(start -0.12065 -0.2794)
			(end 0.12065 -0.2794)
			(stroke
				(width 0.1)
				(type default)
			)
			(layer "F.Fab")
		)
		(fp_line
			(start -0.12065 -0.305054)
			(end -0.12065 -0.2794)
			(stroke
				(width 0.1)
				(type default)
			)
			(layer "F.Fab")
		)
		(fp_line
			(start -0.67945 0.3048)
			(end -0.67945 -0.305054)
			(stroke
				(width 0.1)
				(type default)
			)
			(layer "F.Fab")
		)
		(fp_line
			(start -0.67945 -0.305054)
			(end -0.12065 -0.305054)
			(stroke
				(width 0.1)
				(type default)
			)
			(layer "F.Fab")
		)
		(pad "1" smd circle
			(at -0.40005 0 180)
			(size 0 0)
			(layers "F.Cu" "F.Mask" "F.Paste")
			(net "P3V3_NIC1_CO_GATE")
		)
		(pad "2" smd circle
			(at 0.40005 0 180)
			(size 0 0)
			(layers "F.Cu" "F.Mask" "F.Paste")
			(net "GND")
		)
	)
	(footprint ""
		(layer "F.Cu")
		(at 263.179814 -310.28894 -135)
		(property "Reference" "R1331"
			(at 0 0 225)
			(layer "F.SilkS")
			(hide yes)
			(effects
				(font
					(size 1.27 1.27)
				)
			)
		)
		(property "Value" ""
			(at 0 0 225)
			(layer "F.Fab")
			(effects
				(font
					(size 1.27 1.27)
				)
			)
		)
		(duplicate_pad_numbers_are_jumpers no)
		(fp_line
			(start 0.787389 0.406267)
			(end -0.787389 0.406267)
			(stroke
				(width 0.1524)
				(type default)
			)
			(layer "F.SilkS")
		)
		(fp_line
			(start 0.787389 -0.406267)
			(end 0.787389 0.406267)
			(stroke
				(width 0.1524)
				(type default)
			)
			(layer "F.SilkS")
		)
		(fp_line
			(start -0.787389 0.406267)
			(end -0.787389 -0.406267)
			(stroke
				(width 0.1524)
				(type default)
			)
			(layer "F.SilkS")
		)
		(fp_line
			(start -0.787389 -0.406267)
			(end 0.787389 -0.406267)
			(stroke
				(width 0.1524)
				(type default)
			)
			(layer "F.SilkS")
		)
		(fp_line
			(start 0.679446 0.30479)
			(end 0.120515 0.30479)
			(stroke
				(width 0.1)
				(type default)
			)
			(layer "F.Fab")
		)
		(fp_line
			(start 0.120515 0.30479)
			(end 0.120335 0.279466)
			(stroke
				(width 0.1)
				(type default)
			)
			(layer "F.Fab")
		)
		(fp_line
			(start 0.120335 0.279466)
			(end -0.120695 0.279466)
			(stroke
				(width 0.1)
				(type default)
			)
			(layer "F.Fab")
		)
		(fp_line
			(start 0.679446 -0.30479)
			(end 0.679446 0.30479)
			(stroke
				(width 0.1)
				(type default)
			)
			(layer "F.Fab")
		)
		(fp_line
			(start -0.120515 0.30479)
			(end -0.679446 0.30479)
			(stroke
				(width 0.1)
				(type default)
			)
			(layer "F.Fab")
		)
		(fp_line
			(start -0.120695 0.279466)
			(end -0.120515 0.30479)
			(stroke
				(width 0.1)
				(type default)
			)
			(layer "F.Fab")
		)
		(fp_line
			(start 0.120695 -0.279466)
			(end 0.120515 -0.30479)
			(stroke
				(width 0.1)
				(type default)
			)
			(layer "F.Fab")
		)
		(fp_line
			(start 0.120515 -0.30479)
			(end 0.679446 -0.30479)
			(stroke
				(width 0.1)
				(type default)
			)
			(layer "F.Fab")
		)
		(fp_line
			(start -0.679446 0.30479)
			(end -0.679446 -0.305149)
			(stroke
				(width 0.1)
				(type default)
			)
			(layer "F.Fab")
		)
		(fp_line
			(start -0.120695 -0.279466)
			(end 0.120695 -0.279466)
			(stroke
				(width 0.1)
				(type default)
			)
			(layer "F.Fab")
		)
		(fp_line
			(start -0.120695 -0.304969)
			(end -0.120695 -0.279466)
			(stroke
				(width 0.1)
				(type default)
			)
			(layer "F.Fab")
		)
		(fp_line
			(start -0.679446 -0.305149)
			(end -0.120695 -0.304969)
			(stroke
				(width 0.1)
				(type default)
			)
			(layer "F.Fab")
		)
		(pad "1" smd circle
			(at -0.40005 0 225)
			(size 0 0)
			(layers "F.Cu" "F.Mask" "F.Paste")
			(net "PEX2_DBG_MODE0")
		)
		(pad "2" smd circle
			(at 0.40005 0 225)
			(size 0 0)
			(layers "F.Cu" "F.Mask" "F.Paste")
			(net "P1V8_PEX")
		)
	)
	(footprint ""
		(layer "F.Cu")
		(at 128.848612 -162.003994 90)
		(property "Reference" "PR6899"
			(at 0 0 90)
			(layer "F.SilkS")
			(hide yes)
			(effects
				(font
					(size 1.27 1.27)
				)
			)
		)
		(property "Value" ""
			(at 0 0 90)
			(layer "F.Fab")
			(effects
				(font
					(size 1.27 1.27)
				)
			)
		)
		(duplicate_pad_numbers_are_jumpers no)
		(fp_line
			(start 0.7874 -0.4064)
			(end 0.7874 0.4064)
			(stroke
				(width 0.1524)
				(type default)
			)
			(layer "F.SilkS")
		)
		(fp_line
			(start -0.7874 -0.4064)
			(end 0.7874 -0.4064)
			(stroke
				(width 0.1524)
				(type default)
			)
			(layer "F.SilkS")
		)
		(fp_line
			(start 0.7874 0.4064)
			(end -0.7874 0.4064)
			(stroke
				(width 0.1524)
				(type default)
			)
			(layer "F.SilkS")
		)
		(fp_line
			(start -0.7874 0.4064)
			(end -0.7874 -0.4064)
			(stroke
				(width 0.1524)
				(type default)
			)
			(layer "F.SilkS")
		)
		(fp_line
			(start -0.12065 -0.305054)
			(end -0.12065 -0.2794)
			(stroke
				(width 0.1)
				(type default)
			)
			(layer "F.Fab")
		)
		(fp_line
			(start -0.67945 -0.305054)
			(end -0.12065 -0.305054)
			(stroke
				(width 0.1)
				(type default)
			)
			(layer "F.Fab")
		)
		(fp_line
			(start 0.67945 -0.3048)
			(end 0.67945 0.3048)
			(stroke
				(width 0.1)
				(type default)
			)
			(layer "F.Fab")
		)
		(fp_line
			(start 0.12065 -0.3048)
			(end 0.67945 -0.3048)
			(stroke
				(width 0.1)
				(type default)
			)
			(layer "F.Fab")
		)
		(fp_line
			(start 0.12065 -0.2794)
			(end 0.12065 -0.3048)
			(stroke
				(width 0.1)
				(type default)
			)
			(layer "F.Fab")
		)
		(fp_line
			(start -0.12065 -0.2794)
			(end 0.12065 -0.2794)
			(stroke
				(width 0.1)
				(type default)
			)
			(layer "F.Fab")
		)
		(fp_line
			(start 0.120396 0.2794)
			(end -0.12065 0.2794)
			(stroke
				(width 0.1)
				(type default)
			)
			(layer "F.Fab")
		)
		(fp_line
			(start -0.12065 0.2794)
			(end -0.12065 0.3048)
			(stroke
				(width 0.1)
				(type default)
			)
			(layer "F.Fab")
		)
		(fp_line
			(start 0.67945 0.3048)
			(end 0.120396 0.3048)
			(stroke
				(width 0.1)
				(type default)
			)
			(layer "F.Fab")
		)
		(fp_line
			(start 0.120396 0.3048)
			(end 0.120396 0.2794)
			(stroke
				(width 0.1)
				(type default)
			)
			(layer "F.Fab")
		)
		(fp_line
			(start -0.12065 0.3048)
			(end -0.67945 0.3048)
			(stroke
				(width 0.1)
				(type default)
			)
			(layer "F.Fab")
		)
		(fp_line
			(start -0.67945 0.3048)
			(end -0.67945 -0.305054)
			(stroke
				(width 0.1)
				(type default)
			)
			(layer "F.Fab")
		)
		(pad "1" smd circle
			(at -0.40005 0 90)
			(size 0 0)
			(layers "F.Cu" "F.Mask" "F.Paste")
			(net "P12V_NIC2_CO_ISET")
		)
		(pad "2" smd circle
			(at 0.40005 0 90)
			(size 0 0)
			(layers "F.Cu" "F.Mask" "F.Paste")
			(net "GND")
		)
	)
)
